(kicad_pcb
	(version 20260206)
	(generator "pcbnew")
	(generator_version "10.0")
	(general
		(thickness 1.6)
		(legacy_teardrops no)
	)
	(paper "A4")
	(title_block
		(title "04192023_DAF0TMB3IC0_F0TG_MB_C_brd_V02_OCP.brd")
		(comment 1 "Grand Teton / footprints 1797-1803 of 8354")
	)
	(layers
		(0 "F.Cu" signal "TOP")
		(4 "In1.Cu" signal "GND")
		(6 "In2.Cu" signal "IN1")
		(8 "In3.Cu" signal "GND1")
		(10 "In4.Cu" signal "IN2")
		(12 "In5.Cu" signal "GND2")
		(14 "In6.Cu" signal "IN3")
		(16 "In7.Cu" signal "GND3")
		(18 "In8.Cu" signal "VCC")
		(20 "In9.Cu" signal "VCC1")
		(22 "In10.Cu" signal "GND4")
		(24 "In11.Cu" signal "IN4")
		(26 "In12.Cu" signal "GND5")
		(28 "In13.Cu" signal "IN5")
		(30 "In14.Cu" signal "GND6")
		(32 "In15.Cu" signal "IN6")
		(34 "In16.Cu" signal "GND7")
		(2 "B.Cu" signal "BOTTOM")
		(9 "F.Adhes" user "F.Adhesive")
		(11 "B.Adhes" user "B.Adhesive")
		(13 "F.Paste" user "Package Geometry/Pastemask Top")
		(15 "B.Paste" user "Package Geometry/Pastemask Bottom")
		(5 "F.SilkS" user "Ref Des/Silkscreen Top")
		(7 "B.SilkS" user "Ref Des/Silkscreen Bottom")
		(1 "F.Mask" user "Board Geometry/Soldermask Top")
		(3 "B.Mask" user "Board Geometry/Soldermask Bottom")
		(17 "Dwgs.User" user "User.Drawings")
		(19 "Cmts.User" user "User.Comments")
		(21 "Eco1.User" user "User.Eco1")
		(23 "Eco2.User" user "User.Eco2")
		(25 "Edge.Cuts" user "Board Geometry/Outline")
		(27 "Margin" user)
		(31 "F.CrtYd" user "Package Geometry/Place Bound Top")
		(29 "B.CrtYd" user "Package Geometry/Place Bound Bottom")
		(35 "F.Fab" user "Ref Des/Assembly Top")
		(33 "B.Fab" user "Ref Des/Assembly Bottom")
	)
	(footprint ""
		(layer "F.Cu")
		(at 331.37602 -337.638898 90)
		(property "Reference" "PC79"
			(at 0 0 90)
			(layer "F.SilkS")
			(hide yes)
			(effects
				(font
					(size 1.27 1.27)
				)
			)
		)
		(property "Value" ""
			(at 0 0 90)
			(layer "F.Fab")
			(effects
				(font
					(size 1.27 1.27)
				)
			)
		)
		(duplicate_pad_numbers_are_jumpers no)
		(fp_line
			(start 0.7874 -0.4064)
			(end 0.7874 0.4064)
			(stroke
				(width 0.1524)
				(type default)
			)
			(layer "F.SilkS")
		)
		(fp_line
			(start -0.7874 -0.4064)
			(end 0.7874 -0.4064)
			(stroke
				(width 0.1524)
				(type default)
			)
			(layer "F.SilkS")
		)
		(fp_line
			(start 0.7874 0.4064)
			(end 0.435102 0.4064)
			(stroke
				(width 0.1524)
				(type default)
			)
			(layer "F.SilkS")
		)
		(fp_line
			(start -0.225298 0.4064)
			(end -0.7874 0.4064)
			(stroke
				(width 0.1524)
				(type default)
			)
			(layer "F.SilkS")
		)
		(fp_line
			(start -0.7874 0.4064)
			(end -0.7874 -0.4064)
			(stroke
				(width 0.1524)
				(type default)
			)
			(layer "F.SilkS")
		)
		(fp_line
			(start -0.12065 -0.305054)
			(end -0.12065 -0.2794)
			(stroke
				(width 0.1)
				(type default)
			)
			(layer "F.Fab")
		)
		(fp_line
			(start -0.67945 -0.305054)
			(end -0.12065 -0.305054)
			(stroke
				(width 0.1)
				(type default)
			)
			(layer "F.Fab")
		)
		(fp_line
			(start 0.67945 -0.3048)
			(end 0.67945 0.3048)
			(stroke
				(width 0.1)
				(type default)
			)
			(layer "F.Fab")
		)
		(fp_line
			(start 0.12065 -0.3048)
			(end 0.67945 -0.3048)
			(stroke
				(width 0.1)
				(type default)
			)
			(layer "F.Fab")
		)
		(fp_line
			(start 0.12065 -0.2794)
			(end 0.12065 -0.3048)
			(stroke
				(width 0.1)
				(type default)
			)
			(layer "F.Fab")
		)
		(fp_line
			(start -0.12065 -0.2794)
			(end 0.12065 -0.2794)
			(stroke
				(width 0.1)
				(type default)
			)
			(layer "F.Fab")
		)
		(fp_line
			(start 0.120396 0.2794)
			(end -0.12065 0.2794)
			(stroke
				(width 0.1)
				(type default)
			)
			(layer "F.Fab")
		)
		(fp_line
			(start -0.12065 0.2794)
			(end -0.12065 0.3048)
			(stroke
				(width 0.1)
				(type default)
			)
			(layer "F.Fab")
		)
		(fp_line
			(start 0.67945 0.3048)
			(end 0.120396 0.3048)
			(stroke
				(width 0.1)
				(type default)
			)
			(layer "F.Fab")
		)
		(fp_line
			(start 0.120396 0.3048)
			(end 0.120396 0.2794)
			(stroke
				(width 0.1)
				(type default)
			)
			(layer "F.Fab")
		)
		(fp_line
			(start -0.12065 0.3048)
			(end -0.67945 0.3048)
			(stroke
				(width 0.1)
				(type default)
			)
			(layer "F.Fab")
		)
		(fp_line
			(start -0.67945 0.3048)
			(end -0.67945 -0.305054)
			(stroke
				(width 0.1)
				(type default)
			)
			(layer "F.Fab")
		)
		(pad "1" smd circle
			(at -0.40005 0 90)
			(size 0 0)
			(layers "F.Cu" "F.Mask" "F.Paste")
			(net "PVDDCR_CPU1_P0_VCC1")
		)
		(pad "2" smd circle
			(at 0.40005 0 90)
			(size 0 0)
			(layers "F.Cu" "F.Mask" "F.Paste")
			(net "GND")
		)
	)
	(footprint ""
		(layer "F.Cu")
		(at 43.265852 -384.66268)
		(property "Reference" "R715"
			(at 0 0 0)
			(layer "F.SilkS")
			(hide yes)
			(effects
				(font
					(size 1.27 1.27)
				)
			)
		)
		(property "Value" ""
			(at 0 0 0)
			(layer "F.Fab")
			(effects
				(font
					(size 1.27 1.27)
				)
			)
		)
		(duplicate_pad_numbers_are_jumpers no)
		(fp_line
			(start -0.32512 -0.175006)
			(end 0.32512 -0.175006)
			(stroke
				(width 0.1)
				(type default)
			)
			(layer "F.Fab")
		)
		(fp_line
			(start -0.32512 0.175006)
			(end -0.32512 -0.175006)
			(stroke
				(width 0.1)
				(type default)
			)
			(layer "F.Fab")
		)
		(fp_line
			(start 0.32512 -0.175006)
			(end 0.32512 0.175006)
			(stroke
				(width 0.1)
				(type default)
			)
			(layer "F.Fab")
		)
		(fp_line
			(start 0.32512 0.175006)
			(end -0.32512 0.175006)
			(stroke
				(width 0.1)
				(type default)
			)
			(layer "F.Fab")
		)
		(pad "1" smd rect
			(at -0.2667 0)
			(size 0.3048 0.381)
			(layers "F.Cu" "F.Mask" "F.Paste")
			(net "GPIO3_RT_CPU1_P0")
		)
		(pad "2" smd rect
			(at 0.2667 0 180)
			(size 0.3048 0.381)
			(layers "F.Cu" "F.Mask" "F.Paste")
			(net "GND")
		)
	)
	(footprint ""
		(layer "F.Cu")
		(at 46.548294 -17.623536 90)
		(property "Reference" "C700"
			(at 0 0 90)
			(layer "F.SilkS")
			(hide yes)
			(effects
				(font
					(size 1.27 1.27)
				)
			)
		)
		(property "Value" ""
			(at 0 0 90)
			(layer "F.Fab")
			(effects
				(font
					(size 1.27 1.27)
				)
			)
		)
		(duplicate_pad_numbers_are_jumpers no)
		(fp_line
			(start 0.299974 -0.150114)
			(end 0.299974 0.150114)
			(stroke
				(width 0.1)
				(type default)
			)
			(layer "F.Fab")
		)
		(fp_line
			(start -0.299974 -0.150114)
			(end 0.299974 -0.150114)
			(stroke
				(width 0.1)
				(type default)
			)
			(layer "F.Fab")
		)
		(fp_line
			(start 0.299974 0.150114)
			(end -0.299974 0.150114)
			(stroke
				(width 0.1)
				(type default)
			)
			(layer "F.Fab")
		)
		(fp_line
			(start -0.299974 0.150114)
			(end -0.299974 -0.150114)
			(stroke
				(width 0.1)
				(type default)
			)
			(layer "F.Fab")
		)
		(pad "1" smd rect
			(at -0.2667 0 90)
			(size 0.3048 0.381)
			(layers "F.Cu" "F.Mask" "F.Paste")
			(net "P5E_CPU1_G1_TX_C_DN<4>")
		)
		(pad "2" smd rect
			(at 0.2667 0 90)
			(size 0.3048 0.381)
			(layers "F.Cu" "F.Mask" "F.Paste")
			(net "P5E_CPU1_G1_TX_DN<4>")
		)
	)
	(footprint ""
		(layer "F.Cu")
		(at 216.9668 -101.92512 180)
		(property "Reference" "C9050"
			(at 0 0 180)
			(layer "F.SilkS")
			(hide yes)
			(effects
				(font
					(size 1.27 1.27)
				)
			)
		)
		(property "Value" ""
			(at 0 0 180)
			(layer "F.Fab")
			(effects
				(font
					(size 1.27 1.27)
				)
			)
		)
		(duplicate_pad_numbers_are_jumpers no)
		(fp_line
			(start 0.7874 0.4064)
			(end -0.7874 0.4064)
			(stroke
				(width 0.1524)
				(type default)
			)
			(layer "F.SilkS")
		)
		(fp_line
			(start 0.7874 -0.4064)
			(end 0.7874 0.4064)
			(stroke
				(width 0.1524)
				(type default)
			)
			(layer "F.SilkS")
		)
		(fp_line
			(start -0.7874 0.4064)
			(end -0.7874 -0.4064)
			(stroke
				(width 0.1524)
				(type default)
			)
			(layer "F.SilkS")
		)
		(fp_line
			(start -0.7874 -0.4064)
			(end 0.7874 -0.4064)
			(stroke
				(width 0.1524)
				(type default)
			)
			(layer "F.SilkS")
		)
		(fp_line
			(start 0.67945 0.3048)
			(end 0.120396 0.3048)
			(stroke
				(width 0.1)
				(type default)
			)
			(layer "F.Fab")
		)
		(fp_line
			(start 0.67945 -0.3048)
			(end 0.67945 0.3048)
			(stroke
				(width 0.1)
				(type default)
			)
			(layer "F.Fab")
		)
		(fp_line
			(start 0.12065 -0.2794)
			(end 0.12065 -0.3048)
			(stroke
				(width 0.1)
				(type default)
			)
			(layer "F.Fab")
		)
		(fp_line
			(start 0.12065 -0.3048)
			(end 0.67945 -0.3048)
			(stroke
				(width 0.1)
				(type default)
			)
			(layer "F.Fab")
		)
		(fp_line
			(start 0.120396 0.3048)
			(end 0.120396 0.2794)
			(stroke
				(width 0.1)
				(type default)
			)
			(layer "F.Fab")
		)
		(fp_line
			(start 0.120396 0.2794)
			(end -0.12065 0.2794)
			(stroke
				(width 0.1)
				(type default)
			)
			(layer "F.Fab")
		)
		(fp_line
			(start -0.12065 0.3048)
			(end -0.67945 0.3048)
			(stroke
				(width 0.1)
				(type default)
			)
			(layer "F.Fab")
		)
		(fp_line
			(start -0.12065 0.2794)
			(end -0.12065 0.3048)
			(stroke
				(width 0.1)
				(type default)
			)
			(layer "F.Fab")
		)
		(fp_line
			(start -0.12065 -0.2794)
			(end 0.12065 -0.2794)
			(stroke
				(width 0.1)
				(type default)
			)
			(layer "F.Fab")
		)
		(fp_line
			(start -0.12065 -0.305054)
			(end -0.12065 -0.2794)
			(stroke
				(width 0.1)
				(type default)
			)
			(layer "F.Fab")
		)
		(fp_line
			(start -0.67945 0.3048)
			(end -0.67945 -0.305054)
			(stroke
				(width 0.1)
				(type default)
			)
			(layer "F.Fab")
		)
		(fp_line
			(start -0.67945 -0.305054)
			(end -0.12065 -0.305054)
			(stroke
				(width 0.1)
				(type default)
			)
			(layer "F.Fab")
		)
		(pad "1" smd circle
			(at -0.40005 0 180)
			(size 0 0)
			(layers "F.Cu" "F.Mask" "F.Paste")
			(net "P3V3_AUX")
		)
		(pad "2" smd circle
			(at 0.40005 0 180)
			(size 0 0)
			(layers "F.Cu" "F.Mask" "F.Paste")
			(net "GND")
		)
	)
	(footprint ""
		(layer "F.Cu")
		(at 302.241458 -114.859308)
		(property "Reference" "R68"
			(at 0 0 0)
			(layer "F.SilkS")
			(hide yes)
			(effects
				(font
					(size 1.27 1.27)
				)
			)
		)
		(property "Value" ""
			(at 0 0 0)
			(layer "F.Fab")
			(effects
				(font
					(size 1.27 1.27)
				)
			)
		)
		(duplicate_pad_numbers_are_jumpers no)
		(fp_line
			(start -0.7874 -0.4064)
			(end 0.7874 -0.4064)
			(stroke
				(width 0.1524)
				(type default)
			)
			(layer "F.SilkS")
		)
		(fp_line
			(start -0.7874 0.4064)
			(end -0.7874 -0.4064)
			(stroke
				(width 0.1524)
				(type default)
			)
			(layer "F.SilkS")
		)
		(fp_line
			(start 0.7874 -0.4064)
			(end 0.7874 0.4064)
			(stroke
				(width 0.1524)
				(type default)
			)
			(layer "F.SilkS")
		)
		(fp_line
			(start 0.7874 0.4064)
			(end -0.7874 0.4064)
			(stroke
				(width 0.1524)
				(type default)
			)
			(layer "F.SilkS")
		)
		(fp_line
			(start -0.67945 -0.305054)
			(end -0.12065 -0.305054)
			(stroke
				(width 0.1)
				(type default)
			)
			(layer "F.Fab")
		)
		(fp_line
			(start -0.67945 0.3048)
			(end -0.67945 -0.305054)
			(stroke
				(width 0.1)
				(type default)
			)
			(layer "F.Fab")
		)
		(fp_line
			(start -0.12065 -0.305054)
			(end -0.12065 -0.2794)
			(stroke
				(width 0.1)
				(type default)
			)
			(layer "F.Fab")
		)
		(fp_line
			(start -0.12065 -0.2794)
			(end 0.12065 -0.2794)
			(stroke
				(width 0.1)
				(type default)
			)
			(layer "F.Fab")
		)
		(fp_line
			(start -0.12065 0.2794)
			(end -0.12065 0.3048)
			(stroke
				(width 0.1)
				(type default)
			)
			(layer "F.Fab")
		)
		(fp_line
			(start -0.12065 0.3048)
			(end -0.67945 0.3048)
			(stroke
				(width 0.1)
				(type default)
			)
			(layer "F.Fab")
		)
		(fp_line
			(start 0.120396 0.2794)
			(end -0.12065 0.2794)
			(stroke
				(width 0.1)
				(type default)
			)
			(layer "F.Fab")
		)
		(fp_line
			(start 0.120396 0.3048)
			(end 0.120396 0.2794)
			(stroke
				(width 0.1)
				(type default)
			)
			(layer "F.Fab")
		)
		(fp_line
			(start 0.12065 -0.3048)
			(end 0.67945 -0.3048)
			(stroke
				(width 0.1)
				(type default)
			)
			(layer "F.Fab")
		)
		(fp_line
			(start 0.12065 -0.2794)
			(end 0.12065 -0.3048)
			(stroke
				(width 0.1)
				(type default)
			)
			(layer "F.Fab")
		)
		(fp_line
			(start 0.67945 -0.3048)
			(end 0.67945 0.3048)
			(stroke
				(width 0.1)
				(type default)
			)
			(layer "F.Fab")
		)
		(fp_line
			(start 0.67945 0.3048)
			(end 0.120396 0.3048)
			(stroke
				(width 0.1)
				(type default)
			)
			(layer "F.Fab")
		)
		(pad "1" smd circle
			(at -0.40005 0)
			(size 0 0)
			(layers "F.Cu" "F.Mask" "F.Paste")
			(net "P3V3_AUX")
		)
		(pad "2" smd circle
			(at 0.40005 0)
			(size 0 0)
			(layers "F.Cu" "F.Mask" "F.Paste")
			(net "CPU_FRU_ADDR0")
		)
	)
	(footprint ""
		(layer "F.Cu")
		(at 188.849 -100.294948 90)
		(property "Reference" "R183"
			(at 0 0 90)
			(layer "F.SilkS")
			(hide yes)
			(effects
				(font
					(size 1.27 1.27)
				)
			)
		)
		(property "Value" ""
			(at 0 0 90)
			(layer "F.Fab")
			(effects
				(font
					(size 1.27 1.27)
				)
			)
		)
		(duplicate_pad_numbers_are_jumpers no)
		(fp_line
			(start 0.7874 -0.4064)
			(end 0.7874 0.4064)
			(stroke
				(width 0.1524)
				(type default)
			)
			(layer "F.SilkS")
		)
		(fp_line
			(start -0.7874 -0.4064)
			(end 0.7874 -0.4064)
			(stroke
				(width 0.1524)
				(type default)
			)
			(layer "F.SilkS")
		)
		(fp_line
			(start 0.7874 0.4064)
			(end -0.7874 0.4064)
			(stroke
				(width 0.1524)
				(type default)
			)
			(layer "F.SilkS")
		)
		(fp_line
			(start -0.7874 0.4064)
			(end -0.7874 -0.4064)
			(stroke
				(width 0.1524)
				(type default)
			)
			(layer "F.SilkS")
		)
		(fp_line
			(start -0.12065 -0.305054)
			(end -0.12065 -0.2794)
			(stroke
				(width 0.1)
				(type default)
			)
			(layer "F.Fab")
		)
		(fp_line
			(start -0.67945 -0.305054)
			(end -0.12065 -0.305054)
			(stroke
				(width 0.1)
				(type default)
			)
			(layer "F.Fab")
		)
		(fp_line
			(start 0.67945 -0.3048)
			(end 0.67945 0.3048)
			(stroke
				(width 0.1)
				(type default)
			)
			(layer "F.Fab")
		)
		(fp_line
			(start 0.12065 -0.3048)
			(end 0.67945 -0.3048)
			(stroke
				(width 0.1)
				(type default)
			)
			(layer "F.Fab")
		)
		(fp_line
			(start 0.12065 -0.2794)
			(end 0.12065 -0.3048)
			(stroke
				(width 0.1)
				(type default)
			)
			(layer "F.Fab")
		)
		(fp_line
			(start -0.12065 -0.2794)
			(end 0.12065 -0.2794)
			(stroke
				(width 0.1)
				(type default)
			)
			(layer "F.Fab")
		)
		(fp_line
			(start 0.120396 0.2794)
			(end -0.12065 0.2794)
			(stroke
				(width 0.1)
				(type default)
			)
			(layer "F.Fab")
		)
		(fp_line
			(start -0.12065 0.2794)
			(end -0.12065 0.3048)
			(stroke
				(width 0.1)
				(type default)
			)
			(layer "F.Fab")
		)
		(fp_line
			(start 0.67945 0.3048)
			(end 0.120396 0.3048)
			(stroke
				(width 0.1)
				(type default)
			)
			(layer "F.Fab")
		)
		(fp_line
			(start 0.120396 0.3048)
			(end 0.120396 0.2794)
			(stroke
				(width 0.1)
				(type default)
			)
			(layer "F.Fab")
		)
		(fp_line
			(start -0.12065 0.3048)
			(end -0.67945 0.3048)
			(stroke
				(width 0.1)
				(type default)
			)
			(layer "F.Fab")
		)
		(fp_line
			(start -0.67945 0.3048)
			(end -0.67945 -0.305054)
			(stroke
				(width 0.1)
				(type default)
			)
			(layer "F.Fab")
		)
		(pad "1" smd circle
			(at -0.40005 0 90)
			(size 0 0)
			(layers "F.Cu" "F.Mask" "F.Paste")
			(net "CPU0_CORETYPE0")
		)
		(pad "2" smd circle
			(at 0.40005 0 90)
			(size 0 0)
			(layers "F.Cu" "F.Mask" "F.Paste")
			(net "FM_CPU0_CORETYPE0")
		)
	)
	(footprint ""
		(layer "F.Cu")
		(at 171.196 -122.646948)
		(property "Reference" "R6030"
			(at 0 0 0)
			(layer "F.SilkS")
			(hide yes)
			(effects
				(font
					(size 1.27 1.27)
				)
			)
		)
		(property "Value" ""
			(at 0 0 0)
			(layer "F.Fab")
			(effects
				(font
					(size 1.27 1.27)
				)
			)
		)
		(duplicate_pad_numbers_are_jumpers no)
		(fp_line
			(start -0.7874 -0.4064)
			(end 0.7874 -0.4064)
			(stroke
				(width 0.1524)
				(type default)
			)
			(layer "F.SilkS")
		)
		(fp_line
			(start -0.7874 0.4064)
			(end -0.7874 -0.4064)
			(stroke
				(width 0.1524)
				(type default)
			)
			(layer "F.SilkS")
		)
		(fp_line
			(start 0.7874 -0.4064)
			(end 0.7874 0.4064)
			(stroke
				(width 0.1524)
				(type default)
			)
			(layer "F.SilkS")
		)
		(fp_line
			(start 0.7874 0.4064)
			(end -0.7874 0.4064)
			(stroke
				(width 0.1524)
				(type default)
			)
			(layer "F.SilkS")
		)
		(fp_line
			(start -0.67945 -0.305054)
			(end -0.12065 -0.305054)
			(stroke
				(width 0.1)
				(type default)
			)
			(layer "F.Fab")
		)
		(fp_line
			(start -0.67945 0.3048)
			(end -0.67945 -0.305054)
			(stroke
				(width 0.1)
				(type default)
			)
			(layer "F.Fab")
		)
		(fp_line
			(start -0.12065 -0.305054)
			(end -0.12065 -0.2794)
			(stroke
				(width 0.1)
				(type default)
			)
			(layer "F.Fab")
		)
		(fp_line
			(start -0.12065 -0.2794)
			(end 0.12065 -0.2794)
			(stroke
				(width 0.1)
				(type default)
			)
			(layer "F.Fab")
		)
		(fp_line
			(start -0.12065 0.2794)
			(end -0.12065 0.3048)
			(stroke
				(width 0.1)
				(type default)
			)
			(layer "F.Fab")
		)
		(fp_line
			(start -0.12065 0.3048)
			(end -0.67945 0.3048)
			(stroke
				(width 0.1)
				(type default)
			)
			(layer "F.Fab")
		)
		(fp_line
			(start 0.120396 0.2794)
			(end -0.12065 0.2794)
			(stroke
				(width 0.1)
				(type default)
			)
			(layer "F.Fab")
		)
		(fp_line
			(start 0.120396 0.3048)
			(end 0.120396 0.2794)
			(stroke
				(width 0.1)
				(type default)
			)
			(layer "F.Fab")
		)
		(fp_line
			(start 0.12065 -0.3048)
			(end 0.67945 -0.3048)
			(stroke
				(width 0.1)
				(type default)
			)
			(layer "F.Fab")
		)
		(fp_line
			(start 0.12065 -0.2794)
			(end 0.12065 -0.3048)
			(stroke
				(width 0.1)
				(type default)
			)
			(layer "F.Fab")
		)
		(fp_line
			(start 0.67945 -0.3048)
			(end 0.67945 0.3048)
			(stroke
				(width 0.1)
				(type default)
			)
			(layer "F.Fab")
		)
		(fp_line
			(start 0.67945 0.3048)
			(end 0.120396 0.3048)
			(stroke
				(width 0.1)
				(type default)
			)
			(layer "F.Fab")
		)
		(pad "1" smd circle
			(at -0.40005 0)
			(size 0 0)
			(layers "F.Cu" "F.Mask" "F.Paste")
			(net "CLK_GEN2_GPU_FPGA_OE_N")
		)
		(pad "2" smd circle
			(at 0.40005 0)
			(size 0 0)
			(layers "F.Cu" "F.Mask" "F.Paste")
			(net "CLK_GEN2_GPU_FPGA_OE_R_N")
		)
	)
)
